(kicad_pcb
	(version 20260206)
	(generator "pcbnew")
	(generator_version "10.0")
	(general
		(thickness 1.6)
		(legacy_teardrops no)
	)
	(paper "A4")
	(title_block
		(title "Wiwynn_Tioga_Pass_MB.brd")
		(comment 1 "Tioga Pass / footprints 162-168 of 4770")
	)
	(layers
		(0 "F.Cu" signal "TOP")
		(4 "In1.Cu" signal "L2GND")
		(6 "In2.Cu" signal "L3")
		(8 "In3.Cu" signal "L4GND")
		(10 "In4.Cu" signal "L5")
		(12 "In5.Cu" signal "L6GND")
		(14 "In6.Cu" signal "L7VCC")
		(16 "In7.Cu" signal "L8VCC")
		(18 "In8.Cu" signal "L9GND")
		(20 "In9.Cu" signal "L10")
		(22 "In10.Cu" signal "L11GND")
		(24 "In11.Cu" signal "L12")
		(26 "In12.Cu" signal "L13GND")
		(2 "B.Cu" signal "BOTTOM")
		(9 "F.Adhes" user "F.Adhesive")
		(11 "B.Adhes" user "B.Adhesive")
		(13 "F.Paste" user "Package Geometry/Pastemask Top")
		(15 "B.Paste" user "Package Geometry/Pastemask Bottom")
		(5 "F.SilkS" user "Ref Des/Silkscreen Top")
		(7 "B.SilkS" user "Ref Des/Silkscreen Bottom")
		(1 "F.Mask" user "Board Geometry/Soldermask Top")
		(3 "B.Mask" user "Board Geometry/Soldermask Bottom")
		(17 "Dwgs.User" user "User.Drawings")
		(19 "Cmts.User" user "User.Comments")
		(21 "Eco1.User" user "User.Eco1")
		(23 "Eco2.User" user "User.Eco2")
		(25 "Edge.Cuts" user "Board Geometry/Outline")
		(27 "Margin" user)
		(31 "F.CrtYd" user "Package Geometry/Place Bound Top")
		(29 "B.CrtYd" user "Package Geometry/Place Bound Bottom")
		(35 "F.Fab" user "Ref Des/Assembly Top")
		(33 "B.Fab" user "Ref Des/Assembly Bottom")
	)
	(footprint ""
		(layer "F.Cu")
		(at 9.398 -68.0593 180)
		(property "Reference" "R1D46"
			(at 0 0 180)
			(layer "F.SilkS")
			(hide yes)
			(effects
				(font
					(size 1.27 1.27)
				)
			)
		)
		(property "Value" ""
			(at 0 0 180)
			(layer "F.Fab")
			(effects
				(font
					(size 1.27 1.27)
				)
			)
		)
		(duplicate_pad_numbers_are_jumpers no)
		(fp_rect
			(start 0.2794 0.9906)
			(end -0.2794 -0.1016)
			(stroke
				(width 0)
				(type default)
			)
			(fill no)
			(layer "F.CrtYd")
		)
		(fp_line
			(start 0.2794 0.9906)
			(end 0.2794 -0.1016)
			(stroke
				(width 0.1)
				(type default)
			)
			(layer "F.Fab")
		)
		(fp_line
			(start 0.2794 -0.1016)
			(end -0.2794 -0.1016)
			(stroke
				(width 0.1)
				(type default)
			)
			(layer "F.Fab")
		)
		(fp_line
			(start -0.2794 0.9906)
			(end 0.2794 0.9906)
			(stroke
				(width 0.1)
				(type default)
			)
			(layer "F.Fab")
		)
		(fp_line
			(start -0.2794 -0.1016)
			(end -0.2794 0.9906)
			(stroke
				(width 0.1)
				(type default)
			)
			(layer "F.Fab")
		)
		(pad "1" smd rect
			(at 0 0 180)
			(size 0.508 0.508)
			(layers "F.Cu" "F.Mask" "F.Paste")
			(net "P12V_HSC_SENP0")
		)
		(pad "2" smd rect
			(at 0 0.889 180)
			(size 0.508 0.508)
			(layers "F.Cu" "F.Mask" "F.Paste")
			(net "A_HSC_HSP")
		)
		(zone
			(layer "F.Cu")
			(hatch none 0.5)
			(connect_pads
				(clearance 0)
			)
			(min_thickness 0.25)
			(keepout
				(tracks not_allowed)
				(vias allowed)
				(pads allowed)
				(copperpour not_allowed)
				(footprints allowed)
			)
			(placement
				(enabled no)
				(sheetname "")
			)
			(fill
				(thermal_gap 0.5)
				(thermal_bridge_width 0.5)
				(island_removal_mode 0)
			)
			(polygon
				(pts
					(xy 9.144 -68.6943) (xy 9.144 -68.3133) (xy 9.652 -68.3133) (xy 9.652 -68.6943)
				)
			)
		)
		(zone
			(layer "F.Cu")
			(hatch none 0.5)
			(connect_pads
				(clearance 0)
			)
			(min_thickness 0.25)
			(keepout
				(tracks allowed)
				(vias not_allowed)
				(pads allowed)
				(copperpour not_allowed)
				(footprints allowed)
			)
			(placement
				(enabled no)
				(sheetname "")
			)
			(fill
				(thermal_gap 0.5)
				(thermal_bridge_width 0.5)
				(island_removal_mode 0)
			)
			(polygon
				(pts
					(xy 9.144 -68.6943) (xy 9.144 -68.3133) (xy 9.652 -68.3133) (xy 9.652 -68.6943)
				)
			)
		)
	)
	(footprint ""
		(layer "F.Cu")
		(at 25.654 -30.861 90)
		(property "Reference" "R1F1"
			(at 0 0 90)
			(layer "F.SilkS")
			(hide yes)
			(effects
				(font
					(size 1.27 1.27)
				)
			)
		)
		(property "Value" ""
			(at 0 0 90)
			(layer "F.Fab")
			(effects
				(font
					(size 1.27 1.27)
				)
			)
		)
		(duplicate_pad_numbers_are_jumpers no)
		(fp_rect
			(start 0.2794 0.9906)
			(end -0.2794 -0.1016)
			(stroke
				(width 0)
				(type default)
			)
			(fill no)
			(layer "F.CrtYd")
		)
		(fp_line
			(start 0.2794 -0.1016)
			(end -0.2794 -0.1016)
			(stroke
				(width 0.1)
				(type default)
			)
			(layer "F.Fab")
		)
		(fp_line
			(start -0.2794 -0.1016)
			(end -0.2794 0.9906)
			(stroke
				(width 0.1)
				(type default)
			)
			(layer "F.Fab")
		)
		(fp_line
			(start 0.2794 0.9906)
			(end 0.2794 -0.1016)
			(stroke
				(width 0.1)
				(type default)
			)
			(layer "F.Fab")
		)
		(fp_line
			(start -0.2794 0.9906)
			(end 0.2794 0.9906)
			(stroke
				(width 0.1)
				(type default)
			)
			(layer "F.Fab")
		)
		(pad "1" smd rect
			(at 0 0 90)
			(size 0.508 0.508)
			(layers "F.Cu" "F.Mask" "F.Paste")
			(net "P3V3_STBY")
		)
		(pad "2" smd rect
			(at 0 0.889 90)
			(size 0.508 0.508)
			(layers "F.Cu" "F.Mask" "F.Paste")
			(net "FAN_TACH0")
		)
		(zone
			(layer "F.Cu")
			(hatch none 0.5)
			(connect_pads
				(clearance 0)
			)
			(min_thickness 0.25)
			(keepout
				(tracks not_allowed)
				(vias allowed)
				(pads allowed)
				(copperpour not_allowed)
				(footprints allowed)
			)
			(placement
				(enabled no)
				(sheetname "")
			)
			(fill
				(thermal_gap 0.5)
				(thermal_bridge_width 0.5)
				(island_removal_mode 0)
			)
			(polygon
				(pts
					(xy 26.289 -31.115) (xy 25.908 -31.115) (xy 25.908 -30.607) (xy 26.289 -30.607)
				)
			)
		)
		(zone
			(layer "F.Cu")
			(hatch none 0.5)
			(connect_pads
				(clearance 0)
			)
			(min_thickness 0.25)
			(keepout
				(tracks allowed)
				(vias not_allowed)
				(pads allowed)
				(copperpour not_allowed)
				(footprints allowed)
			)
			(placement
				(enabled no)
				(sheetname "")
			)
			(fill
				(thermal_gap 0.5)
				(thermal_bridge_width 0.5)
				(island_removal_mode 0)
			)
			(polygon
				(pts
					(xy 26.289 -31.115) (xy 25.908 -31.115) (xy 25.908 -30.607) (xy 26.289 -30.607)
				)
			)
		)
	)
	(footprint ""
		(layer "F.Cu")
		(at 407.878026 -66.758566)
		(property "Reference" "R8E9"
			(at 0 0 0)
			(layer "F.SilkS")
			(hide yes)
			(effects
				(font
					(size 1.27 1.27)
				)
			)
		)
		(property "Value" ""
			(at 0 0 0)
			(layer "F.Fab")
			(effects
				(font
					(size 1.27 1.27)
				)
			)
		)
		(duplicate_pad_numbers_are_jumpers no)
		(fp_poly
			(pts
				(xy -0.2794 -0.1016) (xy 0.2794 -0.1016) (xy 0.2794 0.9906) (xy -0.2794 0.9906)
			)
			(stroke
				(width 0)
				(type default)
			)
			(fill no)
			(layer "F.CrtYd")
		)
		(pad "1" smd rect
			(at 0 0)
			(size 0.508 0.508)
			(layers "F.Cu" "F.Mask" "F.Paste")
			(net "SPI_PCH_CLK")
		)
		(pad "2" smd rect
			(at 0 0.889)
			(size 0.508 0.508)
			(layers "F.Cu" "F.Mask" "F.Paste")
			(net "SPI_PCH_TPM_CLK_R")
		)
		(zone
			(layer "F.Cu")
			(hatch none 0.5)
			(connect_pads
				(clearance 0)
			)
			(min_thickness 0.25)
			(keepout
				(tracks allowed)
				(vias not_allowed)
				(pads allowed)
				(copperpour not_allowed)
				(footprints allowed)
			)
			(placement
				(enabled no)
				(sheetname "")
			)
			(fill
				(thermal_gap 0.5)
				(thermal_bridge_width 0.5)
				(island_removal_mode 0)
			)
			(polygon
				(pts
					(xy 407.624026 -66.504566) (xy 408.132026 -66.504566) (xy 408.132026 -66.123566) (xy 407.624026 -66.123566)
				)
			)
		)
		(zone
			(layer "F.Cu")
			(hatch none 0.5)
			(connect_pads
				(clearance 0)
			)
			(min_thickness 0.25)
			(keepout
				(tracks not_allowed)
				(vias allowed)
				(pads allowed)
				(copperpour not_allowed)
				(footprints allowed)
			)
			(placement
				(enabled no)
				(sheetname "")
			)
			(fill
				(thermal_gap 0.5)
				(thermal_bridge_width 0.5)
				(island_removal_mode 0)
			)
			(polygon
				(pts
					(xy 407.624026 -66.123566) (xy 408.132026 -66.123566) (xy 408.132026 -66.504566) (xy 407.624026 -66.504566)
				)
			)
		)
	)
	(footprint ""
		(layer "F.Cu")
		(at 167.386 -120.0658 90)
		(property "Reference" "C4B14"
			(at 3.27533 5.1054 0)
			(unlocked yes)
			(layer "F.SilkS")
			(effects
				(font
					(size 0.7874 0.5842)
					(thickness 0.1524)
				)
			)
		)
		(property "Value" ""
			(at 0 0 90)
			(layer "F.Fab")
			(effects
				(font
					(size 1.27 1.27)
				)
			)
		)
		(duplicate_pad_numbers_are_jumpers no)
		(fp_line
			(start 2.504948 -1.616456)
			(end 2.504948 1.633728)
			(stroke
				(width 0.1524)
				(type default)
			)
			(layer "F.SilkS")
		)
		(fp_line
			(start 1.6002 -1.616456)
			(end 2.504948 -1.616456)
			(stroke
				(width 0.1524)
				(type default)
			)
			(layer "F.SilkS")
		)
		(fp_line
			(start -1.6002 -1.616456)
			(end -2.563114 -1.616456)
			(stroke
				(width 0.1524)
				(type default)
			)
			(layer "F.SilkS")
		)
		(fp_line
			(start -2.563114 -1.616456)
			(end -2.563114 1.633728)
			(stroke
				(width 0.1524)
				(type default)
			)
			(layer "F.SilkS")
		)
		(fp_line
			(start 2.504948 1.633728)
			(end 1.6002 1.633728)
			(stroke
				(width 0.1524)
				(type default)
			)
			(layer "F.SilkS")
		)
		(fp_line
			(start -2.563114 1.633728)
			(end -1.6002 1.633728)
			(stroke
				(width 0.1524)
				(type default)
			)
			(layer "F.SilkS")
		)
		(fp_line
			(start 2.286 7.366)
			(end 2.286 1.63195)
			(stroke
				(width 0.1524)
				(type default)
			)
			(layer "F.SilkS")
		)
		(fp_line
			(start 2.286 7.366)
			(end 1.600708 7.366)
			(stroke
				(width 0.1524)
				(type default)
			)
			(layer "F.SilkS")
		)
		(fp_line
			(start -2.286 7.366)
			(end -2.286 1.632712)
			(stroke
				(width 0.1524)
				(type default)
			)
			(layer "F.SilkS")
		)
		(fp_line
			(start -2.286 7.366)
			(end -1.60147 7.366)
			(stroke
				(width 0.1524)
				(type default)
			)
			(layer "F.SilkS")
		)
		(fp_rect
			(start -2.286 7.366)
			(end 2.286 -0.254)
			(stroke
				(width 0)
				(type default)
			)
			(fill no)
			(layer "F.CrtYd")
		)
		(fp_line
			(start 2.286 -0.254)
			(end 2.286 7.366)
			(stroke
				(width 0.1)
				(type default)
			)
			(layer "F.Fab")
		)
		(fp_line
			(start -2.286 -0.254)
			(end 2.286 -0.254)
			(stroke
				(width 0.1)
				(type default)
			)
			(layer "F.Fab")
		)
		(fp_line
			(start 2.286 7.366)
			(end -2.286 7.366)
			(stroke
				(width 0.1)
				(type default)
			)
			(layer "F.Fab")
		)
		(fp_line
			(start -2.286 7.366)
			(end -2.286 -0.254)
			(stroke
				(width 0.1)
				(type default)
			)
			(layer "F.Fab")
		)
		(pad "1" smd rect
			(at 0 0 90)
			(size 2.54 3.048)
			(layers "F.Cu" "F.Mask" "F.Paste")
			(net "P12V_STBY")
		)
		(pad "2" smd rect
			(at 0 7.112 90)
			(size 2.54 3.048)
			(layers "F.Cu" "F.Mask" "F.Paste")
			(net "GND")
		)
	)
	(footprint ""
		(layer "F.Cu")
		(at 321.16522 -119.26316 90)
		(property "Reference" "C6B12"
			(at -0.8382 -0.67818 90)
			(unlocked yes)
			(layer "F.SilkS")
			(effects
				(font
					(size 0.4064 0.254)
					(thickness 0.1524)
				)
				(justify left)
			)
		)
		(property "Value" ""
			(at 0 0 90)
			(layer "F.Fab")
			(effects
				(font
					(size 1.27 1.27)
				)
			)
		)
		(duplicate_pad_numbers_are_jumpers no)
		(fp_poly
			(pts
				(xy 0.3048 -0.1016) (xy 0.3048 0.9906) (xy -0.3048 0.9906) (xy -0.3048 -0.1016)
			)
			(stroke
				(width 0)
				(type default)
			)
			(fill no)
			(layer "F.CrtYd")
		)
		(fp_line
			(start 0.3048 -0.1016)
			(end -0.3048 -0.1016)
			(stroke
				(width 0.1)
				(type default)
			)
			(layer "F.Fab")
		)
		(fp_line
			(start -0.3048 -0.1016)
			(end -0.3048 0.9906)
			(stroke
				(width 0.1)
				(type default)
			)
			(layer "F.Fab")
		)
		(fp_line
			(start 0.3048 0.9906)
			(end 0.3048 -0.1016)
			(stroke
				(width 0.1)
				(type default)
			)
			(layer "F.Fab")
		)
		(fp_line
			(start -0.3048 0.9906)
			(end 0.3048 0.9906)
			(stroke
				(width 0.1)
				(type default)
			)
			(layer "F.Fab")
		)
		(pad "1" smd rect
			(at 0 0 90)
			(size 0.508 0.508)
			(layers "F.Cu" "F.Mask" "F.Paste")
			(net "P3E_CPU0_PE1_PCH_TXP<12>")
		)
		(pad "2" smd rect
			(at 0 0.889 90)
			(size 0.508 0.508)
			(layers "F.Cu" "F.Mask" "F.Paste")
			(net "P3E_CPU0_PE1_PCH_C_TXP<12>")
		)
		(zone
			(layer "F.Cu")
			(hatch none 0.5)
			(connect_pads
				(clearance 0)
			)
			(min_thickness 0.25)
			(keepout
				(tracks allowed)
				(vias not_allowed)
				(pads allowed)
				(copperpour not_allowed)
				(footprints allowed)
			)
			(placement
				(enabled no)
				(sheetname "")
			)
			(fill
				(thermal_gap 0.5)
				(thermal_bridge_width 0.5)
				(island_removal_mode 0)
			)
			(polygon
				(pts
					(xy 321.41922 -119.00916) (xy 321.41922 -119.51716) (xy 321.80022 -119.51716) (xy 321.80022 -119.00916)
				)
			)
		)
		(zone
			(layer "F.Cu")
			(hatch none 0.5)
			(connect_pads
				(clearance 0)
			)
			(min_thickness 0.25)
			(keepout
				(tracks not_allowed)
				(vias allowed)
				(pads allowed)
				(copperpour not_allowed)
				(footprints allowed)
			)
			(placement
				(enabled no)
				(sheetname "")
			)
			(fill
				(thermal_gap 0.5)
				(thermal_bridge_width 0.5)
				(island_removal_mode 0)
			)
			(polygon
				(pts
					(xy 321.80022 -119.00916) (xy 321.80022 -119.51716) (xy 321.41922 -119.51716) (xy 321.41922 -119.00916)
				)
			)
		)
	)
	(footprint ""
		(layer "F.Cu")
		(at 33.178496 -53.221382 90)
		(property "Reference" "C1E7"
			(at 0 0 90)
			(layer "F.SilkS")
			(hide yes)
			(effects
				(font
					(size 1.27 1.27)
				)
			)
		)
		(property "Value" ""
			(at 0 0 90)
			(layer "F.Fab")
			(effects
				(font
					(size 1.27 1.27)
				)
			)
		)
		(duplicate_pad_numbers_are_jumpers no)
		(fp_rect
			(start 0.3048 0.9906)
			(end -0.3048 -0.1016)
			(stroke
				(width 0)
				(type default)
			)
			(fill no)
			(layer "F.CrtYd")
		)
		(fp_line
			(start 0.3048 -0.1016)
			(end -0.3048 -0.1016)
			(stroke
				(width 0.1)
				(type default)
			)
			(layer "F.Fab")
		)
		(fp_line
			(start -0.3048 -0.1016)
			(end -0.3048 0.9906)
			(stroke
				(width 0.1)
				(type default)
			)
			(layer "F.Fab")
		)
		(fp_line
			(start 0.3048 0.9906)
			(end 0.3048 -0.1016)
			(stroke
				(width 0.1)
				(type default)
			)
			(layer "F.Fab")
		)
		(fp_line
			(start -0.3048 0.9906)
			(end 0.3048 0.9906)
			(stroke
				(width 0.1)
				(type default)
			)
			(layer "F.Fab")
		)
		(pad "1" smd rect
			(at 0 0 90)
			(size 0.508 0.508)
			(layers "F.Cu" "F.Mask" "F.Paste")
			(net "P5V_STBY")
		)
		(pad "2" smd rect
			(at 0 0.889 90)
			(size 0.508 0.508)
			(layers "F.Cu" "F.Mask" "F.Paste")
			(net "GND")
		)
		(zone
			(layer "F.Cu")
			(hatch none 0.5)
			(connect_pads
				(clearance 0)
			)
			(min_thickness 0.25)
			(keepout
				(tracks allowed)
				(vias not_allowed)
				(pads allowed)
				(copperpour not_allowed)
				(footprints allowed)
			)
			(placement
				(enabled no)
				(sheetname "")
			)
			(fill
				(thermal_gap 0.5)
				(thermal_bridge_width 0.5)
				(island_removal_mode 0)
			)
			(polygon
				(pts
					(xy 33.813496 -53.475382) (xy 33.432496 -53.475382) (xy 33.432496 -52.967382) (xy 33.813496 -52.967382)
				)
			)
		)
		(zone
			(layer "F.Cu")
			(hatch none 0.5)
			(connect_pads
				(clearance 0)
			)
			(min_thickness 0.25)
			(keepout
				(tracks not_allowed)
				(vias allowed)
				(pads allowed)
				(copperpour not_allowed)
				(footprints allowed)
			)
			(placement
				(enabled no)
				(sheetname "")
			)
			(fill
				(thermal_gap 0.5)
				(thermal_bridge_width 0.5)
				(island_removal_mode 0)
			)
			(polygon
				(pts
					(xy 33.813496 -53.475382) (xy 33.432496 -53.475382) (xy 33.432496 -52.967382) (xy 33.813496 -52.967382)
				)
			)
		)
	)
	(footprint ""
		(layer "F.Cu")
		(at 444.1825 -146.5834 -90)
		(property "Reference" "C25W92"
			(at -0.8382 -0.67818 270)
			(unlocked yes)
			(layer "F.SilkS")
			(effects
				(font
					(size 0.4064 0.254)
					(thickness 0.1524)
				)
				(justify left)
			)
		)
		(property "Value" ""
			(at 0 0 270)
			(layer "F.Fab")
			(effects
				(font
					(size 1.27 1.27)
				)
			)
		)
		(duplicate_pad_numbers_are_jumpers no)
		(fp_poly
			(pts
				(xy 0.3048 -0.1016) (xy 0.3048 0.9906) (xy -0.3048 0.9906) (xy -0.3048 -0.1016)
			)
			(stroke
				(width 0)
				(type default)
			)
			(fill no)
			(layer "F.CrtYd")
		)
		(fp_line
			(start -0.3048 0.9906)
			(end 0.3048 0.9906)
			(stroke
				(width 0.1)
				(type default)
			)
			(layer "F.Fab")
		)
		(fp_line
			(start 0.3048 0.9906)
			(end 0.3048 -0.1016)
			(stroke
				(width 0.1)
				(type default)
			)
			(layer "F.Fab")
		)
		(fp_line
			(start -0.3048 -0.1016)
			(end -0.3048 0.9906)
			(stroke
				(width 0.1)
				(type default)
			)
			(layer "F.Fab")
		)
		(fp_line
			(start 0.3048 -0.1016)
			(end -0.3048 -0.1016)
			(stroke
				(width 0.1)
				(type default)
			)
			(layer "F.Fab")
		)
		(pad "1" smd rect
			(at 0 0 270)
			(size 0.508 0.508)
			(layers "F.Cu" "F.Mask" "F.Paste")
			(net "P3V3_STBY")
		)
		(pad "2" smd rect
			(at 0 0.889 270)
			(size 0.508 0.508)
			(layers "F.Cu" "F.Mask" "F.Paste")
			(net "GND")
		)
		(zone
			(layer "F.Cu")
			(hatch none 0.5)
			(connect_pads
				(clearance 0)
			)
			(min_thickness 0.25)
			(keepout
				(tracks not_allowed)
				(vias allowed)
				(pads allowed)
				(copperpour not_allowed)
				(footprints allowed)
			)
			(placement
				(enabled no)
				(sheetname "")
			)
			(fill
				(thermal_gap 0.5)
				(thermal_bridge_width 0.5)
				(island_removal_mode 0)
			)
			(polygon
				(pts
					(xy 443.5475 -146.8374) (xy 443.5475 -146.3294) (xy 443.9285 -146.3294) (xy 443.9285 -146.8374)
				)
			)
		)
		(zone
			(layer "F.Cu")
			(hatch none 0.5)
			(connect_pads
				(clearance 0)
			)
			(min_thickness 0.25)
			(keepout
				(tracks allowed)
				(vias not_allowed)
				(pads allowed)
				(copperpour not_allowed)
				(footprints allowed)
			)
			(placement
				(enabled no)
				(sheetname "")
			)
			(fill
				(thermal_gap 0.5)
				(thermal_bridge_width 0.5)
				(island_removal_mode 0)
			)
			(polygon
				(pts
					(xy 443.9285 -146.8374) (xy 443.9285 -146.3294) (xy 443.5475 -146.3294) (xy 443.5475 -146.8374)
				)
			)
		)
	)
)
